#ISCELL
  cls sheet_a1 *
  *
#ISCELL
  cls gnd_sg *
  page68_i1
#CELL
  passive resistor *
  page68_i10
#CELL
  passive resistor *
  page68_i11
#ISCELL
  cls vcc *
  page68_i12
#ISCELL
  cls offpage_out *
  page68_i13
#CELL
  passive resistor *
  page68_i14
#ISCELL
  cls gnd_sg *
  page68_i15
#CELL
  passive resistor *
  page68_i16
#ISCELL
  cls gnd_sg *
  page68_i17
#CELL
  passive resistor *
  page68_i18
#ISCELL
  cls offpage_in *
  page68_i19
#CELL
  passive resistor *
  page68_i2
#ISCELL
  cls vcc *
  page68_i20
#ISCELL
  cls offpage_in *
  page68_i23
#ISCELL
  cls vcc *
  page68_i24
#CELL
  passive ferritebead *
  page68_i25
#CELL
  passive resistor *
  page68_i26
#CELL
  passive capacitor *
  page68_i27
#CELL
  passive capacitor *
  page68_i3
#ISCELL
  cls gnd_sg *
  page68_i34
#CELL
  passive capacitor *
  page68_i35
#ISCELL
  cls gnd_sg *
  page68_i4
#ISCELL
  cls gnd_sg *
  page68_i41
#CELL
  passive resistor *
  page68_i42
#CELL
  passive ferritebead *
  page68_i43
#CELL
  passive resistor *
  page68_i44
#CELL
  passive resistor *
  page68_i45
#CELL
  passive capacitor *
  page68_i46
#CELL
  passive capacitor *
  page68_i47
#ISCELL
  cls gnd_sg *
  page68_i48
#CELL
  passive capacitor *
  page68_i49
#CELL
  passive capacitor *
  page68_i5
#ISCELL
  cls gnd_sg *
  page68_i50
#CELL
  passive capacitor *
  page68_i51
#CELL
  analog isl80101irajz_dfn10 *
  page68_i52
#CELL
  passive resistor *
  page68_i59
#CELL
  analog isl80101irajz_dfn10 *
  page68_i6
#CELL
  passive capacitor *
  page68_i60
#CELL
  passive capacitor *
  page68_i61
#ISCELL
  cls gnd_sg *
  page68_i7
#ISCELL
  cls gnd_sg *
  page68_i70
#CELL
  passive capacitor *
  page68_i71
#ISCELL
  cls gnd_sg *
  page68_i72
#CELL
  passive resistor *
  page68_i73
#CELL
  passive resistor *
  page68_i74
#ISCELL
  cls vcc *
  page68_i75
#ISCELL
  cls gnd_sg *
  page68_i77
#CELL
  passive resistor *
  page68_i78
#CELL
  passive resistor *
  page68_i79
#ISCELL
  cls gnd_sg *
  page68_i8
#CELL
  passive resistor *
  page68_i80
#CELL
  passive capacitor *
  page68_i81
#ISCELL
  cls gnd_sg *
  page68_i82
#CELL
  passive capacitor *
  page68_i83
#ISCELL
  cls vcc *
  page68_i84
#ISCELL
  cls vcc *
  page68_i86
#CELL
  passive capacitor *
  page68_i9
#ISCELL
  cls offpage_out *
  page68_i92
#CELL
  passive capacitor *
  page68_i93
#CELL
  passive capacitor *
  page68_i94
#ISCELL
  cls gnd_sg *
  page68_i95
#ISCELL
  cls gnd_sg *
  page68_i96
#CELL
  passive capacitor *
  page68_i97
#CELL
  passive capacitor *
  page68_i98
